(kicad_pcb
	(version 20260206)
	(generator "pcbnew")
	(generator_version "10.0")
	(general
		(thickness 1.6)
		(legacy_teardrops no)
	)
	(paper "A4")
	(title_block
		(title "01162023_DA0F0TEBIF0_F0T_Expander_BD_F_brd_V02_OCP.brd")
		(comment 1 "Grand Teton / footprints 1836-1839 of 9728")
	)
	(layers
		(0 "F.Cu" signal "TOP")
		(4 "In1.Cu" signal "GND")
		(6 "In2.Cu" signal "VCC")
		(8 "In3.Cu" signal "VCC1")
		(10 "In4.Cu" signal "GND1")
		(12 "In5.Cu" signal "IN1")
		(14 "In6.Cu" signal "GND2")
		(16 "In7.Cu" signal "IN2")
		(18 "In8.Cu" signal "GND3")
		(20 "In9.Cu" signal "IN3")
		(22 "In10.Cu" signal "GND4")
		(24 "In11.Cu" signal "IN4")
		(26 "In12.Cu" signal "GND5")
		(28 "In13.Cu" signal "IN5")
		(30 "In14.Cu" signal "GND6")
		(32 "In15.Cu" signal "IN6")
		(34 "In16.Cu" signal "GND7")
		(2 "B.Cu" signal "BOTTOM")
		(9 "F.Adhes" user "F.Adhesive")
		(11 "B.Adhes" user "B.Adhesive")
		(13 "F.Paste" user "Package Geometry/Pastemask Top")
		(15 "B.Paste" user "Package Geometry/Pastemask Bottom")
		(5 "F.SilkS" user "Ref Des/Silkscreen Top")
		(7 "B.SilkS" user "Ref Des/Silkscreen Bottom")
		(1 "F.Mask" user "Board Geometry/Soldermask Top")
		(3 "B.Mask" user "Board Geometry/Soldermask Bottom")
		(17 "Dwgs.User" user "User.Drawings")
		(19 "Cmts.User" user "User.Comments")
		(21 "Eco1.User" user "User.Eco1")
		(23 "Eco2.User" user "User.Eco2")
		(25 "Edge.Cuts" user "Board Geometry/Outline")
		(27 "Margin" user)
		(31 "F.CrtYd" user "Package Geometry/Place Bound Top")
		(29 "B.CrtYd" user "Package Geometry/Place Bound Bottom")
		(35 "F.Fab" user "Ref Des/Assembly Top")
		(33 "B.Fab" user "Ref Des/Assembly Bottom")
	)
	(footprint ""
		(layer "F.Cu")
		(at 320.17589 -306.075842 90)
		(property "Reference" "R3974"
			(at 0 0 90)
			(layer "F.SilkS")
			(hide yes)
			(effects
				(font
					(size 1.27 1.27)
				)
			)
		)
		(property "Value" ""
			(at 0 0 90)
			(layer "F.Fab")
			(effects
				(font
					(size 1.27 1.27)
				)
			)
		)
		(duplicate_pad_numbers_are_jumpers no)
		(fp_line
			(start 0.7874 -0.4064)
			(end 0.7874 0.4064)
			(stroke
				(width 0.1524)
				(type default)
			)
			(layer "F.SilkS")
		)
		(fp_line
			(start -0.7874 -0.4064)
			(end 0.7874 -0.4064)
			(stroke
				(width 0.1524)
				(type default)
			)
			(layer "F.SilkS")
		)
		(fp_line
			(start 0.7874 0.4064)
			(end -0.7874 0.4064)
			(stroke
				(width 0.1524)
				(type default)
			)
			(layer "F.SilkS")
		)
		(fp_line
			(start -0.7874 0.4064)
			(end -0.7874 -0.4064)
			(stroke
				(width 0.1524)
				(type default)
			)
			(layer "F.SilkS")
		)
		(fp_line
			(start -0.12065 -0.305054)
			(end -0.12065 -0.2794)
			(stroke
				(width 0.1)
				(type default)
			)
			(layer "F.Fab")
		)
		(fp_line
			(start -0.67945 -0.305054)
			(end -0.12065 -0.305054)
			(stroke
				(width 0.1)
				(type default)
			)
			(layer "F.Fab")
		)
		(fp_line
			(start 0.67945 -0.3048)
			(end 0.67945 0.3048)
			(stroke
				(width 0.1)
				(type default)
			)
			(layer "F.Fab")
		)
		(fp_line
			(start 0.12065 -0.3048)
			(end 0.67945 -0.3048)
			(stroke
				(width 0.1)
				(type default)
			)
			(layer "F.Fab")
		)
		(fp_line
			(start 0.12065 -0.2794)
			(end 0.12065 -0.3048)
			(stroke
				(width 0.1)
				(type default)
			)
			(layer "F.Fab")
		)
		(fp_line
			(start -0.12065 -0.2794)
			(end 0.12065 -0.2794)
			(stroke
				(width 0.1)
				(type default)
			)
			(layer "F.Fab")
		)
		(fp_line
			(start 0.120396 0.2794)
			(end -0.12065 0.2794)
			(stroke
				(width 0.1)
				(type default)
			)
			(layer "F.Fab")
		)
		(fp_line
			(start -0.12065 0.2794)
			(end -0.12065 0.3048)
			(stroke
				(width 0.1)
				(type default)
			)
			(layer "F.Fab")
		)
		(fp_line
			(start 0.67945 0.3048)
			(end 0.120396 0.3048)
			(stroke
				(width 0.1)
				(type default)
			)
			(layer "F.Fab")
		)
		(fp_line
			(start 0.120396 0.3048)
			(end 0.120396 0.2794)
			(stroke
				(width 0.1)
				(type default)
			)
			(layer "F.Fab")
		)
		(fp_line
			(start -0.12065 0.3048)
			(end -0.67945 0.3048)
			(stroke
				(width 0.1)
				(type default)
			)
			(layer "F.Fab")
		)
		(fp_line
			(start -0.67945 0.3048)
			(end -0.67945 -0.305054)
			(stroke
				(width 0.1)
				(type default)
			)
			(layer "F.Fab")
		)
		(pad "1" smd circle
			(at -0.40005 0 90)
			(size 0 0)
			(layers "F.Cu" "F.Mask" "F.Paste")
			(net "SMB_PEX2_SLAVE_SDA")
		)
		(pad "2" smd circle
			(at 0.40005 0 90)
			(size 0 0)
			(layers "F.Cu" "F.Mask" "F.Paste")
			(net "SMB_PEX2_R_SDA")
		)
	)
	(footprint ""
		(layer "F.Cu")
		(at 9.62914 -313.51347 180)
		(property "Reference" "PC205"
			(at 0 0 180)
			(layer "F.SilkS")
			(hide yes)
			(effects
				(font
					(size 1.27 1.27)
				)
			)
		)
		(property "Value" ""
			(at 0 0 180)
			(layer "F.Fab")
			(effects
				(font
					(size 1.27 1.27)
				)
			)
		)
		(duplicate_pad_numbers_are_jumpers no)
		(fp_line
			(start 1.524 0.762)
			(end -1.524 0.762)
			(stroke
				(width 0.1524)
				(type default)
			)
			(layer "F.SilkS")
		)
		(fp_line
			(start 1.524 -0.762)
			(end 1.524 0.762)
			(stroke
				(width 0.1524)
				(type default)
			)
			(layer "F.SilkS")
		)
		(fp_line
			(start -1.524 0.762)
			(end -1.524 -0.762)
			(stroke
				(width 0.1524)
				(type default)
			)
			(layer "F.SilkS")
		)
		(fp_line
			(start -1.524 -0.762)
			(end 1.524 -0.762)
			(stroke
				(width 0.1524)
				(type default)
			)
			(layer "F.SilkS")
		)
		(fp_line
			(start 1.1049 0.724916)
			(end 1.1049 -0.724916)
			(stroke
				(width 0.1)
				(type default)
			)
			(layer "F.Fab")
		)
		(fp_line
			(start 1.1049 -0.724916)
			(end -1.1049 -0.724916)
			(stroke
				(width 0.1)
				(type default)
			)
			(layer "F.Fab")
		)
		(fp_line
			(start -1.1049 0.724916)
			(end 1.1049 0.724916)
			(stroke
				(width 0.1)
				(type default)
			)
			(layer "F.Fab")
		)
		(fp_line
			(start -1.1049 -0.724916)
			(end -1.1049 0.724916)
			(stroke
				(width 0.1)
				(type default)
			)
			(layer "F.Fab")
		)
		(pad "1" smd rect
			(at -0.889 0)
			(size 1.016 1.27)
			(layers "F.Cu" "F.Mask" "F.Paste")
			(net "SW_P12V_P1V25_PEX0_FLT")
		)
		(pad "2" smd rect
			(at 0.889 0)
			(size 1.016 1.27)
			(layers "F.Cu" "F.Mask" "F.Paste")
			(net "GND")
		)
	)
	(footprint ""
		(layer "F.Cu")
		(at 464.09991 -313.85002)
		(property "Reference" "H137"
			(at -2.322068 -4.41071 0)
			(unlocked yes)
			(layer "F.SilkS")
			(effects
				(font
					(size 0.7874 0.5842)
					(thickness 0.1524)
				)
				(justify left)
			)
		)
		(property "Value" ""
			(at 0 0 0)
			(layer "F.Fab")
			(effects
				(font
					(size 1.27 1.27)
				)
			)
		)
		(duplicate_pad_numbers_are_jumpers no)
		(pad "1" thru_hole circle
			(at 0 0)
			(size 6.5024 6.5024)
			(drill 3.2004)
			(layers "*.Cu" "*.Mask")
			(remove_unused_layers no)
			(net "GND")
			(clearance -1.397)
		)
	)
	(footprint ""
		(layer "F.Cu")
		(at 89.851992 -289.230816 90)
		(property "Reference" "R3880"
			(at 0 0 90)
			(layer "F.SilkS")
			(hide yes)
			(effects
				(font
					(size 1.27 1.27)
				)
			)
		)
		(property "Value" ""
			(at 0 0 90)
			(layer "F.Fab")
			(effects
				(font
					(size 1.27 1.27)
				)
			)
		)
		(duplicate_pad_numbers_are_jumpers no)
		(fp_line
			(start 0.7874 -0.4064)
			(end 0.7874 0.4064)
			(stroke
				(width 0.1524)
				(type default)
			)
			(layer "F.SilkS")
		)
		(fp_line
			(start -0.7874 -0.4064)
			(end 0.7874 -0.4064)
			(stroke
				(width 0.1524)
				(type default)
			)
			(layer "F.SilkS")
		)
		(fp_line
			(start 0.7874 0.4064)
			(end -0.7874 0.4064)
			(stroke
				(width 0.1524)
				(type default)
			)
			(layer "F.SilkS")
		)
		(fp_line
			(start -0.7874 0.4064)
			(end -0.7874 -0.4064)
			(stroke
				(width 0.1524)
				(type default)
			)
			(layer "F.SilkS")
		)
		(fp_line
			(start -0.12065 -0.305054)
			(end -0.12065 -0.2794)
			(stroke
				(width 0.1)
				(type default)
			)
			(layer "F.Fab")
		)
		(fp_line
			(start -0.67945 -0.305054)
			(end -0.12065 -0.305054)
			(stroke
				(width 0.1)
				(type default)
			)
			(layer "F.Fab")
		)
		(fp_line
			(start 0.67945 -0.3048)
			(end 0.67945 0.3048)
			(stroke
				(width 0.1)
				(type default)
			)
			(layer "F.Fab")
		)
		(fp_line
			(start 0.12065 -0.3048)
			(end 0.67945 -0.3048)
			(stroke
				(width 0.1)
				(type default)
			)
			(layer "F.Fab")
		)
		(fp_line
			(start 0.12065 -0.2794)
			(end 0.12065 -0.3048)
			(stroke
				(width 0.1)
				(type default)
			)
			(layer "F.Fab")
		)
		(fp_line
			(start -0.12065 -0.2794)
			(end 0.12065 -0.2794)
			(stroke
				(width 0.1)
				(type default)
			)
			(layer "F.Fab")
		)
		(fp_line
			(start 0.120396 0.2794)
			(end -0.12065 0.2794)
			(stroke
				(width 0.1)
				(type default)
			)
			(layer "F.Fab")
		)
		(fp_line
			(start -0.12065 0.2794)
			(end -0.12065 0.3048)
			(stroke
				(width 0.1)
				(type default)
			)
			(layer "F.Fab")
		)
		(fp_line
			(start 0.67945 0.3048)
			(end 0.120396 0.3048)
			(stroke
				(width 0.1)
				(type default)
			)
			(layer "F.Fab")
		)
		(fp_line
			(start 0.120396 0.3048)
			(end 0.120396 0.2794)
			(stroke
				(width 0.1)
				(type default)
			)
			(layer "F.Fab")
		)
		(fp_line
			(start -0.12065 0.3048)
			(end -0.67945 0.3048)
			(stroke
				(width 0.1)
				(type default)
			)
			(layer "F.Fab")
		)
		(fp_line
			(start -0.67945 0.3048)
			(end -0.67945 -0.305054)
			(stroke
				(width 0.1)
				(type default)
			)
			(layer "F.Fab")
		)
		(pad "1" smd circle
			(at -0.40005 0 90)
			(size 0 0)
			(layers "F.Cu" "F.Mask" "F.Paste")
			(net "SMB_PEX0_PCA9555_SDA")
		)
		(pad "2" smd circle
			(at 0.40005 0 90)
			(size 0 0)
			(layers "F.Cu" "F.Mask" "F.Paste")
			(net "SMB_PEX0_HOST_LS_SDA")
		)
	)
)
